# T6G (Grand Teton) — schematic netlist excerpt (pin names and nets, part order shuffled) for the footprints in the layout excerpt that follows; sources: Cadence DE-HDL packaged netlist, KiCad conversion of 04192023_DAF0TMB3IC0_F0TG_MB_C_brd_V02_OCP.brd

PR3969  Q_RES  2.49K 1% CHIP  pkg 0402LF  page 146 : A = P3V3_E1S_CB_0 ; B = GND
PR6601  Q_RES  0 5% CHIP  pkg 0402LF  page 364 : A = P0V9_RETIMER_CPU1_SENSE_SH_P ; B = P0V9_RETIMER_CPU1_SENSE_R_P

(kicad_pcb
	(version 20260206)
	(generator "pcbnew")
	(generator_version "10.0")
	(general
		(thickness 1.6)
		(legacy_teardrops no)
	)
	(paper "A4")
	(title_block
		(title "04192023_DAF0TMB3IC0_F0TG_MB_C_brd_V02_OCP.brd")
		(comment 1 "Grand Teton / footprints 2457-2458 of 8354")
	)
	(layers
		(0 "F.Cu" signal "TOP")
		(4 "In1.Cu" signal "GND")
		(6 "In2.Cu" signal "IN1")
		(8 "In3.Cu" signal "GND1")
		(10 "In4.Cu" signal "IN2")
		(12 "In5.Cu" signal "GND2")
		(14 "In6.Cu" signal "IN3")
		(16 "In7.Cu" signal "GND3")
		(18 "In8.Cu" signal "VCC")
		(20 "In9.Cu" signal "VCC1")
		(22 "In10.Cu" signal "GND4")
		(24 "In11.Cu" signal "IN4")
		(26 "In12.Cu" signal "GND5")
		(28 "In13.Cu" signal "IN5")
		(30 "In14.Cu" signal "GND6")
		(32 "In15.Cu" signal "IN6")
		(34 "In16.Cu" signal "GND7")
		(2 "B.Cu" signal "BOTTOM")
		(9 "F.Adhes" user "F.Adhesive")
		(11 "B.Adhes" user "B.Adhesive")
		(13 "F.Paste" user "Package Geometry/Pastemask Top")
		(15 "B.Paste" user "Package Geometry/Pastemask Bottom")
		(5 "F.SilkS" user "Ref Des/Silkscreen Top")
		(7 "B.SilkS" user "Ref Des/Silkscreen Bottom")
		(1 "F.Mask" user "Board Geometry/Soldermask Top")
		(3 "B.Mask" user "Board Geometry/Soldermask Bottom")
		(17 "Dwgs.User" user "User.Drawings")
		(19 "Cmts.User" user "User.Comments")
		(21 "Eco1.User" user "User.Eco1")
		(23 "Eco2.User" user "User.Eco2")
		(25 "Edge.Cuts" user "Board Geometry/Outline")
		(27 "Margin" user)
		(31 "F.CrtYd" user "Package Geometry/Place Bound Top")
		(29 "B.CrtYd" user "Package Geometry/Place Bound Bottom")
		(35 "F.Fab" user "Ref Des/Assembly Top")
		(33 "B.Fab" user "Ref Des/Assembly Bottom")
	)
	(footprint ""
		(layer "F.Cu")
		(at 218.011502 -71.126858 180)
		(property "Reference" "PR3969"
			(at 0 0 180)
			(layer "F.SilkS")
			(hide yes)
			(effects
				(font
					(size 1.27 1.27)
				)
			)
		)
		(property "Value" ""
			(at 0 0 180)
			(layer "F.Fab")
			(effects
				(font
					(size 1.27 1.27)
				)
			)
		)
		(duplicate_pad_numbers_are_jumpers no)
		(fp_line
			(start 0.7874 0.4064)
			(end -0.7874 0.4064)
			(stroke
				(width 0.1524)
				(type default)
			)
			(layer "F.SilkS")
		)
		(fp_line
			(start 0.7874 -0.4064)
			(end 0.7874 0.4064)
			(stroke
				(width 0.1524)
				(type default)
			)
			(layer "F.SilkS")
		)
		(fp_line
			(start -0.7874 0.4064)
			(end -0.7874 -0.4064)
			(stroke
				(width 0.1524)
				(type default)
			)
			(layer "F.SilkS")
		)
		(fp_line
			(start -0.7874 -0.4064)
			(end 0.7874 -0.4064)
			(stroke
				(width 0.1524)
				(type default)
			)
			(layer "F.SilkS")
		)
		(fp_line
			(start 0.67945 0.3048)
			(end 0.120396 0.3048)
			(stroke
				(width 0.1)
				(type default)
			)
			(layer "F.Fab")
		)
		(fp_line
			(start 0.67945 -0.3048)
			(end 0.67945 0.3048)
			(stroke
				(width 0.1)
				(type default)
			)
			(layer "F.Fab")
		)
		(fp_line
			(start 0.12065 -0.2794)
			(end 0.12065 -0.3048)
			(stroke
				(width 0.1)
				(type default)
			)
			(layer "F.Fab")
		)
		(fp_line
			(start 0.12065 -0.3048)
			(end 0.67945 -0.3048)
			(stroke
				(width 0.1)
				(type default)
			)
			(layer "F.Fab")
		)
		(fp_line
			(start 0.120396 0.3048)
			(end 0.120396 0.2794)
			(stroke
				(width 0.1)
				(type default)
			)
			(layer "F.Fab")
		)
		(fp_line
			(start 0.120396 0.2794)
			(end -0.12065 0.2794)
			(stroke
				(width 0.1)
				(type default)
			)
			(layer "F.Fab")
		)
		(fp_line
			(start -0.12065 0.3048)
			(end -0.67945 0.3048)
			(stroke
				(width 0.1)
				(type default)
			)
			(layer "F.Fab")
		)
		(fp_line
			(start -0.12065 0.2794)
			(end -0.12065 0.3048)
			(stroke
				(width 0.1)
				(type default)
			)
			(layer "F.Fab")
		)
		(fp_line
			(start -0.12065 -0.2794)
			(end 0.12065 -0.2794)
			(stroke
				(width 0.1)
				(type default)
			)
			(layer "F.Fab")
		)
		(fp_line
			(start -0.12065 -0.305054)
			(end -0.12065 -0.2794)
			(stroke
				(width 0.1)
				(type default)
			)
			(layer "F.Fab")
		)
		(fp_line
			(start -0.67945 0.3048)
			(end -0.67945 -0.305054)
			(stroke
				(width 0.1)
				(type default)
			)
			(layer "F.Fab")
		)
		(fp_line
			(start -0.67945 -0.305054)
			(end -0.12065 -0.305054)
			(stroke
				(width 0.1)
				(type default)
			)
			(layer "F.Fab")
		)
		(pad "1" smd circle
			(at -0.40005 0 180)
			(size 0 0)
			(layers "F.Cu" "F.Mask" "F.Paste")
			(net "P3V3_E1S_CB_0")
		)
		(pad "2" smd circle
			(at 0.40005 0 180)
			(size 0 0)
			(layers "F.Cu" "F.Mask" "F.Paste")
			(net "GND")
		)
	)
	(footprint ""
		(layer "F.Cu")
		(at 18.330418 -415.26587 180)
		(property "Reference" "PR6601"
			(at 0 0 180)
			(layer "F.SilkS")
			(hide yes)
			(effects
				(font
					(size 1.27 1.27)
				)
			)
		)
		(property "Value" ""
			(at 0 0 180)
			(layer "F.Fab")
			(effects
				(font
					(size 1.27 1.27)
				)
			)
		)
		(duplicate_pad_numbers_are_jumpers no)
		(fp_line
			(start 0.7874 0.4064)
			(end -0.7874 0.4064)
			(stroke
				(width 0.1524)
				(type default)
			)
			(layer "F.SilkS")
		)
		(fp_line
			(start 0.7874 -0.4064)
			(end 0.7874 0.4064)
			(stroke
				(width 0.1524)
				(type default)
			)
			(layer "F.SilkS")
		)
		(fp_line
			(start -0.7874 0.4064)
			(end -0.7874 -0.4064)
			(stroke
				(width 0.1524)
				(type default)
			)
			(layer "F.SilkS")
		)
		(fp_line
			(start -0.7874 -0.4064)
			(end 0.7874 -0.4064)
			(stroke
				(width 0.1524)
				(type default)
			)
			(layer "F.SilkS")
		)
		(fp_line
			(start 0.67945 0.3048)
			(end 0.120396 0.3048)
			(stroke
				(width 0.1)
				(type default)
			)
			(layer "F.Fab")
		)
		(fp_line
			(start 0.67945 -0.3048)
			(end 0.67945 0.3048)
			(stroke
				(width 0.1)
				(type default)
			)
			(layer "F.Fab")
		)
		(fp_line
			(start 0.12065 -0.2794)
			(end 0.12065 -0.3048)
			(stroke
				(width 0.1)
				(type default)
			)
			(layer "F.Fab")
		)
		(fp_line
			(start 0.12065 -0.3048)
			(end 0.67945 -0.3048)
			(stroke
				(width 0.1)
				(type default)
			)
			(layer "F.Fab")
		)
		(fp_line
			(start 0.120396 0.3048)
			(end 0.120396 0.2794)
			(stroke
				(width 0.1)
				(type default)
			)
			(layer "F.Fab")
		)
		(fp_line
			(start 0.120396 0.2794)
			(end -0.12065 0.2794)
			(stroke
				(width 0.1)
				(type default)
			)
			(layer "F.Fab")
		)
		(fp_line
			(start -0.12065 0.3048)
			(end -0.67945 0.3048)
			(stroke
				(width 0.1)
				(type default)
			)
			(layer "F.Fab")
		)
		(fp_line
			(start -0.12065 0.2794)
			(end -0.12065 0.3048)
			(stroke
				(width 0.1)
				(type default)
			)
			(layer "F.Fab")
		)
		(fp_line
			(start -0.12065 -0.2794)
			(end 0.12065 -0.2794)
			(stroke
				(width 0.1)
				(type default)
			)
			(layer "F.Fab")
		)
		(fp_line
			(start -0.12065 -0.305054)
			(end -0.12065 -0.2794)
			(stroke
				(width 0.1)
				(type default)
			)
			(layer "F.Fab")
		)
		(fp_line
			(start -0.67945 0.3048)
			(end -0.67945 -0.305054)
			(stroke
				(width 0.1)
				(type default)
			)
			(layer "F.Fab")
		)
		(fp_line
			(start -0.67945 -0.305054)
			(end -0.12065 -0.305054)
			(stroke
				(width 0.1)
				(type default)
			)
			(layer "F.Fab")
		)
		(pad "1" smd circle
			(at -0.40005 0 180)
			(size 0 0)
			(layers "F.Cu" "F.Mask" "F.Paste")
			(net "P0V9_RETIMER_CPU1_SENSE_SH_P")
		)
		(pad "2" smd circle
			(at 0.40005 0 180)
			(size 0 0)
			(layers "F.Cu" "F.Mask" "F.Paste")
			(net "P0V9_RETIMER_CPU1_SENSE_R_P")
		)
	)
)
